# T6G (Grand Teton) — schematic netlist excerpt (pin names and nets, part order shuffled) for the footprints in the layout excerpt that follows; sources: Cadence DE-HDL packaged netlist, KiCad conversion of 04192023_DAF0TMB3IC0_F0TG_MB_C_brd_V02_OCP.brd

C6603  Q_CAP_DIFFBUS  DIFF BUS_0.22UF 6.3V 20% X6S  pkg C0201  page 308 : \1\ = P5E_CPU0_P3_TX_BUF_C_DP<3> ; \2\ = P5E_CPU0_P3_TX_BUF_DP<3>
C2118  Q_CAP  22UF 4V 20% X6S  pkg C0402  page 74 : A = PVDD11_S3_P1 ; B = GND
C6036  Q_CAP  0.1UF 25V 10% X7R  pkg 0402  page 177 : A = P1V2_CPU0_USB_DVDD12 ; B = GND

(kicad_pcb
	(version 20260206)
	(generator "pcbnew")
	(generator_version "10.0")
	(general
		(thickness 1.6)
		(legacy_teardrops no)
	)
	(paper "A4")
	(title_block
		(title "04192023_DAF0TMB3IC0_F0TG_MB_C_brd_V02_OCP.brd")
		(comment 1 "Grand Teton / footprints 4981-4983 of 8354")
	)
	(layers
		(0 "F.Cu" signal "TOP")
		(4 "In1.Cu" signal "GND")
		(6 "In2.Cu" signal "IN1")
		(8 "In3.Cu" signal "GND1")
		(10 "In4.Cu" signal "IN2")
		(12 "In5.Cu" signal "GND2")
		(14 "In6.Cu" signal "IN3")
		(16 "In7.Cu" signal "GND3")
		(18 "In8.Cu" signal "VCC")
		(20 "In9.Cu" signal "VCC1")
		(22 "In10.Cu" signal "GND4")
		(24 "In11.Cu" signal "IN4")
		(26 "In12.Cu" signal "GND5")
		(28 "In13.Cu" signal "IN5")
		(30 "In14.Cu" signal "GND6")
		(32 "In15.Cu" signal "IN6")
		(34 "In16.Cu" signal "GND7")
		(2 "B.Cu" signal "BOTTOM")
		(9 "F.Adhes" user "F.Adhesive")
		(11 "B.Adhes" user "B.Adhesive")
		(13 "F.Paste" user "Package Geometry/Pastemask Top")
		(15 "B.Paste" user "Package Geometry/Pastemask Bottom")
		(5 "F.SilkS" user "Ref Des/Silkscreen Top")
		(7 "B.SilkS" user "Ref Des/Silkscreen Bottom")
		(1 "F.Mask" user "Board Geometry/Soldermask Top")
		(3 "B.Mask" user "Board Geometry/Soldermask Bottom")
		(17 "Dwgs.User" user "User.Drawings")
		(19 "Cmts.User" user "User.Comments")
		(21 "Eco1.User" user "User.Eco1")
		(23 "Eco2.User" user "User.Eco2")
		(25 "Edge.Cuts" user "Board Geometry/Outline")
		(27 "Margin" user)
		(31 "F.CrtYd" user "Package Geometry/Place Bound Top")
		(29 "B.CrtYd" user "Package Geometry/Place Bound Bottom")
		(35 "F.Fab" user "Ref Des/Assembly Top")
		(33 "B.Fab" user "Ref Des/Assembly Bottom")
	)
	(footprint ""
		(layer "B.Cu")
		(at 382.504442 -416.899344 90)
		(property "Reference" "C6603"
			(at 0 0 90)
			(layer "B.SilkS")
			(hide yes)
			(effects
				(font
					(size 1.27 1.27)
				)
				(justify mirror)
			)
		)
		(property "Value" ""
			(at 0 0 90)
			(layer "B.Fab")
			(effects
				(font
					(size 1.27 1.27)
				)
				(justify mirror)
			)
		)
		(duplicate_pad_numbers_are_jumpers no)
		(fp_line
			(start 0.299974 -0.150114)
			(end -0.299974 -0.150114)
			(stroke
				(width 0.1)
				(type default)
			)
			(layer "B.Fab")
		)
		(fp_line
			(start -0.299974 -0.150114)
			(end -0.299974 0.150114)
			(stroke
				(width 0.1)
				(type default)
			)
			(layer "B.Fab")
		)
		(fp_line
			(start 0.299974 0.150114)
			(end 0.299974 -0.150114)
			(stroke
				(width 0.1)
				(type default)
			)
			(layer "B.Fab")
		)
		(fp_line
			(start -0.299974 0.150114)
			(end 0.299974 0.150114)
			(stroke
				(width 0.1)
				(type default)
			)
			(layer "B.Fab")
		)
		(pad "1" smd rect
			(at 0.2667 0 270)
			(size 0.3048 0.381)
			(layers "B.Cu" "B.Mask" "B.Paste")
			(net "P5E_CPU0_P3_TX_BUF_C_DP<3>")
		)
		(pad "2" smd rect
			(at -0.2667 0 270)
			(size 0.3048 0.381)
			(layers "B.Cu" "B.Mask" "B.Paste")
			(net "P5E_CPU0_P3_TX_BUF_DP<3>")
		)
	)
	(footprint ""
		(layer "B.Cu")
		(at 136.040114 -36.882578)
		(property "Reference" "C6036"
			(at 0 0 0)
			(layer "B.SilkS")
			(hide yes)
			(effects
				(font
					(size 1.27 1.27)
				)
				(justify mirror)
			)
		)
		(property "Value" ""
			(at 0 0 0)
			(layer "B.Fab")
			(effects
				(font
					(size 1.27 1.27)
				)
				(justify mirror)
			)
		)
		(duplicate_pad_numbers_are_jumpers no)
		(fp_line
			(start -0.7874 -0.4064)
			(end -0.7874 0.4064)
			(stroke
				(width 0.1524)
				(type default)
			)
			(layer "B.SilkS")
		)
		(fp_line
			(start -0.7874 0.4064)
			(end 0.7874 0.4064)
			(stroke
				(width 0.1524)
				(type default)
			)
			(layer "B.SilkS")
		)
		(fp_line
			(start 0.7874 -0.4064)
			(end -0.7874 -0.4064)
			(stroke
				(width 0.1524)
				(type default)
			)
			(layer "B.SilkS")
		)
		(fp_line
			(start 0.7874 0.4064)
			(end 0.7874 -0.4064)
			(stroke
				(width 0.1524)
				(type default)
			)
			(layer "B.SilkS")
		)
		(fp_line
			(start -0.67945 -0.3048)
			(end -0.67945 0.3048)
			(stroke
				(width 0.1)
				(type default)
			)
			(layer "B.Fab")
		)
		(fp_line
			(start -0.67945 0.3048)
			(end -0.120396 0.3048)
			(stroke
				(width 0.1)
				(type default)
			)
			(layer "B.Fab")
		)
		(fp_line
			(start -0.12065 -0.3048)
			(end -0.67945 -0.3048)
			(stroke
				(width 0.1)
				(type default)
			)
			(layer "B.Fab")
		)
		(fp_line
			(start -0.12065 -0.2794)
			(end -0.12065 -0.3048)
			(stroke
				(width 0.1)
				(type default)
			)
			(layer "B.Fab")
		)
		(fp_line
			(start -0.120396 0.2794)
			(end 0.12065 0.2794)
			(stroke
				(width 0.1)
				(type default)
			)
			(layer "B.Fab")
		)
		(fp_line
			(start -0.120396 0.3048)
			(end -0.120396 0.2794)
			(stroke
				(width 0.1)
				(type default)
			)
			(layer "B.Fab")
		)
		(fp_line
			(start 0.12065 -0.305054)
			(end 0.12065 -0.2794)
			(stroke
				(width 0.1)
				(type default)
			)
			(layer "B.Fab")
		)
		(fp_line
			(start 0.12065 -0.2794)
			(end -0.12065 -0.2794)
			(stroke
				(width 0.1)
				(type default)
			)
			(layer "B.Fab")
		)
		(fp_line
			(start 0.12065 0.2794)
			(end 0.12065 0.3048)
			(stroke
				(width 0.1)
				(type default)
			)
			(layer "B.Fab")
		)
		(fp_line
			(start 0.12065 0.3048)
			(end 0.67945 0.3048)
			(stroke
				(width 0.1)
				(type default)
			)
			(layer "B.Fab")
		)
		(fp_line
			(start 0.67945 -0.305054)
			(end 0.12065 -0.305054)
			(stroke
				(width 0.1)
				(type default)
			)
			(layer "B.Fab")
		)
		(fp_line
			(start 0.67945 0.3048)
			(end 0.67945 -0.305054)
			(stroke
				(width 0.1)
				(type default)
			)
			(layer "B.Fab")
		)
		(pad "1" smd circle
			(at 0.40005 0 180)
			(size 0 0)
			(layers "B.Cu" "B.Mask" "B.Paste")
			(net "P1V2_CPU0_USB_DVDD12")
		)
		(pad "2" smd circle
			(at -0.40005 0 180)
			(size 0 0)
			(layers "B.Cu" "B.Mask" "B.Paste")
			(net "GND")
		)
	)
	(footprint ""
		(layer "B.Cu")
		(at 115.864386 -266.005564)
		(property "Reference" "C2118"
			(at 0 0 0)
			(layer "B.SilkS")
			(hide yes)
			(effects
				(font
					(size 1.27 1.27)
				)
				(justify mirror)
			)
		)
		(property "Value" ""
			(at 0 0 0)
			(layer "B.Fab")
			(effects
				(font
					(size 1.27 1.27)
				)
				(justify mirror)
			)
		)
		(duplicate_pad_numbers_are_jumpers no)
		(fp_line
			(start -0.7874 -0.4064)
			(end -0.7874 0.4064)
			(stroke
				(width 0.1524)
				(type default)
			)
			(layer "B.SilkS")
		)
		(fp_line
			(start -0.7874 0.4064)
			(end 0.7874 0.4064)
			(stroke
				(width 0.1524)
				(type default)
			)
			(layer "B.SilkS")
		)
		(fp_line
			(start 0.7874 -0.4064)
			(end -0.7874 -0.4064)
			(stroke
				(width 0.1524)
				(type default)
			)
			(layer "B.SilkS")
		)
		(fp_line
			(start 0.7874 0.4064)
			(end 0.7874 -0.4064)
			(stroke
				(width 0.1524)
				(type default)
			)
			(layer "B.SilkS")
		)
		(fp_line
			(start -0.67945 -0.3048)
			(end -0.67945 0.3048)
			(stroke
				(width 0.1)
				(type default)
			)
			(layer "B.Fab")
		)
		(fp_line
			(start -0.67945 0.3048)
			(end -0.120396 0.3048)
			(stroke
				(width 0.1)
				(type default)
			)
			(layer "B.Fab")
		)
		(fp_line
			(start -0.12065 -0.3048)
			(end -0.67945 -0.3048)
			(stroke
				(width 0.1)
				(type default)
			)
			(layer "B.Fab")
		)
		(fp_line
			(start -0.12065 -0.2794)
			(end -0.12065 -0.3048)
			(stroke
				(width 0.1)
				(type default)
			)
			(layer "B.Fab")
		)
		(fp_line
			(start -0.120396 0.2794)
			(end 0.12065 0.2794)
			(stroke
				(width 0.1)
				(type default)
			)
			(layer "B.Fab")
		)
		(fp_line
			(start -0.120396 0.3048)
			(end -0.120396 0.2794)
			(stroke
				(width 0.1)
				(type default)
			)
			(layer "B.Fab")
		)
		(fp_line
			(start 0.12065 -0.305054)
			(end 0.12065 -0.2794)
			(stroke
				(width 0.1)
				(type default)
			)
			(layer "B.Fab")
		)
		(fp_line
			(start 0.12065 -0.2794)
			(end -0.12065 -0.2794)
			(stroke
				(width 0.1)
				(type default)
			)
			(layer "B.Fab")
		)
		(fp_line
			(start 0.12065 0.2794)
			(end 0.12065 0.3048)
			(stroke
				(width 0.1)
				(type default)
			)
			(layer "B.Fab")
		)
		(fp_line
			(start 0.12065 0.3048)
			(end 0.67945 0.3048)
			(stroke
				(width 0.1)
				(type default)
			)
			(layer "B.Fab")
		)
		(fp_line
			(start 0.67945 -0.305054)
			(end 0.12065 -0.305054)
			(stroke
				(width 0.1)
				(type default)
			)
			(layer "B.Fab")
		)
		(fp_line
			(start 0.67945 0.3048)
			(end 0.67945 -0.305054)
			(stroke
				(width 0.1)
				(type default)
			)
			(layer "B.Fab")
		)
		(pad "1" smd circle
			(at 0.40005 0 180)
			(size 0 0)
			(layers "B.Cu" "B.Mask" "B.Paste")
			(net "PVDD11_S3_P1")
		)
		(pad "2" smd circle
			(at -0.40005 0 180)
			(size 0 0)
			(layers "B.Cu" "B.Mask" "B.Paste")
			(net "GND")
		)
	)
)
